# S9S_MB_2U (Grand Teton) — schematic netlist excerpt (pin names and nets, part order shuffled) for the footprints in the layout excerpt that follows; sources: Cadence DE-HDL packaged netlist, KiCad conversion of 03242023_DA0F0TMBIJ0_F0T_Motherboard_J_brd_V01_OCP.brd

R3106  Q_RES  0 5% CHIP  pkg 0402LF  page 234 : A = SMB_BMC_SWB_SDA ; B = SMB_BMC_SWB_R_SDA
PR73  Q_RES  10K 1% CHIP  pkg 0402LF  page 259 : A = P3V3_AUX ; B = PWRGD_P3V3_AUX

(kicad_pcb
	(version 20260206)
	(generator "pcbnew")
	(generator_version "10.0")
	(general
		(thickness 1.6)
		(legacy_teardrops no)
	)
	(paper "A4")
	(title_block
		(title "03242023_DA0F0TMBIJ0_F0T_Motherboard_J_brd_V01_OCP.brd")
		(comment 1 "Grand Teton / footprints 2054-2055 of 6105")
	)
	(layers
		(0 "F.Cu" signal "TOP")
		(4 "In1.Cu" signal "GND")
		(6 "In2.Cu" signal "IN1")
		(8 "In3.Cu" signal "GND1")
		(10 "In4.Cu" signal "IN2")
		(12 "In5.Cu" signal "GND2")
		(14 "In6.Cu" signal "IN3")
		(16 "In7.Cu" signal "GND3")
		(18 "In8.Cu" signal "VCC")
		(20 "In9.Cu" signal "VCC1")
		(22 "In10.Cu" signal "GND4")
		(24 "In11.Cu" signal "IN4")
		(26 "In12.Cu" signal "GND5")
		(28 "In13.Cu" signal "IN5")
		(30 "In14.Cu" signal "GND6")
		(32 "In15.Cu" signal "IN6")
		(34 "In16.Cu" signal "GND7")
		(2 "B.Cu" signal "BOTTOM")
		(9 "F.Adhes" user "F.Adhesive")
		(11 "B.Adhes" user "B.Adhesive")
		(13 "F.Paste" user "Package Geometry/Pastemask Top")
		(15 "B.Paste" user "Package Geometry/Pastemask Bottom")
		(5 "F.SilkS" user "Ref Des/Silkscreen Top")
		(7 "B.SilkS" user "Ref Des/Silkscreen Bottom")
		(1 "F.Mask" user "Board Geometry/Soldermask Top")
		(3 "B.Mask" user "Board Geometry/Soldermask Bottom")
		(17 "Dwgs.User" user "User.Drawings")
		(19 "Cmts.User" user "User.Comments")
		(21 "Eco1.User" user "User.Eco1")
		(23 "Eco2.User" user "User.Eco2")
		(25 "Edge.Cuts" user "Board Geometry/Outline")
		(27 "Margin" user)
		(31 "F.CrtYd" user "Package Geometry/Place Bound Top")
		(29 "B.CrtYd" user "Package Geometry/Place Bound Bottom")
		(35 "F.Fab" user "Ref Des/Assembly Top")
		(33 "B.Fab" user "Ref Des/Assembly Bottom")
	)
	(footprint ""
		(layer "F.Cu")
		(at 460.6798 -380.691898 90)
		(property "Reference" "PR73"
			(at 0 0 90)
			(layer "F.SilkS")
			(hide yes)
			(effects
				(font
					(size 1.27 1.27)
				)
			)
		)
		(property "Value" ""
			(at 0 0 90)
			(layer "F.Fab")
			(effects
				(font
					(size 1.27 1.27)
				)
			)
		)
		(duplicate_pad_numbers_are_jumpers no)
		(fp_line
			(start 0.7874 -0.4064)
			(end 0.7874 0.4064)
			(stroke
				(width 0.1524)
				(type default)
			)
			(layer "F.SilkS")
		)
		(fp_line
			(start -0.7874 -0.4064)
			(end 0.7874 -0.4064)
			(stroke
				(width 0.1524)
				(type default)
			)
			(layer "F.SilkS")
		)
		(fp_line
			(start 0.7874 0.4064)
			(end -0.7874 0.4064)
			(stroke
				(width 0.1524)
				(type default)
			)
			(layer "F.SilkS")
		)
		(fp_line
			(start -0.7874 0.4064)
			(end -0.7874 -0.4064)
			(stroke
				(width 0.1524)
				(type default)
			)
			(layer "F.SilkS")
		)
		(fp_line
			(start -0.12065 -0.305054)
			(end -0.12065 -0.2794)
			(stroke
				(width 0.1)
				(type default)
			)
			(layer "F.Fab")
		)
		(fp_line
			(start -0.67945 -0.305054)
			(end -0.12065 -0.305054)
			(stroke
				(width 0.1)
				(type default)
			)
			(layer "F.Fab")
		)
		(fp_line
			(start 0.67945 -0.3048)
			(end 0.67945 0.3048)
			(stroke
				(width 0.1)
				(type default)
			)
			(layer "F.Fab")
		)
		(fp_line
			(start 0.12065 -0.3048)
			(end 0.67945 -0.3048)
			(stroke
				(width 0.1)
				(type default)
			)
			(layer "F.Fab")
		)
		(fp_line
			(start 0.12065 -0.2794)
			(end 0.12065 -0.3048)
			(stroke
				(width 0.1)
				(type default)
			)
			(layer "F.Fab")
		)
		(fp_line
			(start -0.12065 -0.2794)
			(end 0.12065 -0.2794)
			(stroke
				(width 0.1)
				(type default)
			)
			(layer "F.Fab")
		)
		(fp_line
			(start 0.120396 0.2794)
			(end -0.12065 0.2794)
			(stroke
				(width 0.1)
				(type default)
			)
			(layer "F.Fab")
		)
		(fp_line
			(start -0.12065 0.2794)
			(end -0.12065 0.3048)
			(stroke
				(width 0.1)
				(type default)
			)
			(layer "F.Fab")
		)
		(fp_line
			(start 0.67945 0.3048)
			(end 0.120396 0.3048)
			(stroke
				(width 0.1)
				(type default)
			)
			(layer "F.Fab")
		)
		(fp_line
			(start 0.120396 0.3048)
			(end 0.120396 0.2794)
			(stroke
				(width 0.1)
				(type default)
			)
			(layer "F.Fab")
		)
		(fp_line
			(start -0.12065 0.3048)
			(end -0.67945 0.3048)
			(stroke
				(width 0.1)
				(type default)
			)
			(layer "F.Fab")
		)
		(fp_line
			(start -0.67945 0.3048)
			(end -0.67945 -0.305054)
			(stroke
				(width 0.1)
				(type default)
			)
			(layer "F.Fab")
		)
		(pad "1" smd circle
			(at -0.40005 0 90)
			(size 0 0)
			(layers "F.Cu" "F.Mask" "F.Paste")
			(net "P3V3_AUX")
		)
		(pad "2" smd circle
			(at 0.40005 0 90)
			(size 0 0)
			(layers "F.Cu" "F.Mask" "F.Paste")
			(net "PWRGD_P3V3_AUX")
		)
	)
	(footprint ""
		(layer "F.Cu")
		(at 163.50615 -418.514276 90)
		(property "Reference" "R3106"
			(at 0 0 90)
			(layer "F.SilkS")
			(hide yes)
			(effects
				(font
					(size 1.27 1.27)
				)
			)
		)
		(property "Value" ""
			(at 0 0 90)
			(layer "F.Fab")
			(effects
				(font
					(size 1.27 1.27)
				)
			)
		)
		(duplicate_pad_numbers_are_jumpers no)
		(fp_line
			(start 0.7874 -0.4064)
			(end 0.7874 0.4064)
			(stroke
				(width 0.1524)
				(type default)
			)
			(layer "F.SilkS")
		)
		(fp_line
			(start -0.7874 -0.4064)
			(end 0.7874 -0.4064)
			(stroke
				(width 0.1524)
				(type default)
			)
			(layer "F.SilkS")
		)
		(fp_line
			(start 0.7874 0.4064)
			(end -0.7874 0.4064)
			(stroke
				(width 0.1524)
				(type default)
			)
			(layer "F.SilkS")
		)
		(fp_line
			(start -0.7874 0.4064)
			(end -0.7874 -0.4064)
			(stroke
				(width 0.1524)
				(type default)
			)
			(layer "F.SilkS")
		)
		(fp_line
			(start -0.12065 -0.305054)
			(end -0.12065 -0.2794)
			(stroke
				(width 0.1)
				(type default)
			)
			(layer "F.Fab")
		)
		(fp_line
			(start -0.67945 -0.305054)
			(end -0.12065 -0.305054)
			(stroke
				(width 0.1)
				(type default)
			)
			(layer "F.Fab")
		)
		(fp_line
			(start 0.67945 -0.3048)
			(end 0.67945 0.3048)
			(stroke
				(width 0.1)
				(type default)
			)
			(layer "F.Fab")
		)
		(fp_line
			(start 0.12065 -0.3048)
			(end 0.67945 -0.3048)
			(stroke
				(width 0.1)
				(type default)
			)
			(layer "F.Fab")
		)
		(fp_line
			(start 0.12065 -0.2794)
			(end 0.12065 -0.3048)
			(stroke
				(width 0.1)
				(type default)
			)
			(layer "F.Fab")
		)
		(fp_line
			(start -0.12065 -0.2794)
			(end 0.12065 -0.2794)
			(stroke
				(width 0.1)
				(type default)
			)
			(layer "F.Fab")
		)
		(fp_line
			(start 0.120396 0.2794)
			(end -0.12065 0.2794)
			(stroke
				(width 0.1)
				(type default)
			)
			(layer "F.Fab")
		)
		(fp_line
			(start -0.12065 0.2794)
			(end -0.12065 0.3048)
			(stroke
				(width 0.1)
				(type default)
			)
			(layer "F.Fab")
		)
		(fp_line
			(start 0.67945 0.3048)
			(end 0.120396 0.3048)
			(stroke
				(width 0.1)
				(type default)
			)
			(layer "F.Fab")
		)
		(fp_line
			(start 0.120396 0.3048)
			(end 0.120396 0.2794)
			(stroke
				(width 0.1)
				(type default)
			)
			(layer "F.Fab")
		)
		(fp_line
			(start -0.12065 0.3048)
			(end -0.67945 0.3048)
			(stroke
				(width 0.1)
				(type default)
			)
			(layer "F.Fab")
		)
		(fp_line
			(start -0.67945 0.3048)
			(end -0.67945 -0.305054)
			(stroke
				(width 0.1)
				(type default)
			)
			(layer "F.Fab")
		)
		(pad "1" smd circle
			(at -0.40005 0 90)
			(size 0 0)
			(layers "F.Cu" "F.Mask" "F.Paste")
			(net "SMB_BMC_SWB_SDA")
		)
		(pad "2" smd circle
			(at 0.40005 0 90)
			(size 0 0)
			(layers "F.Cu" "F.Mask" "F.Paste")
			(net "SMB_BMC_SWB_R_SDA")
		)
	)
)
